(kicad_pcb
	(version 20260206)
	(generator "pcbnew")
	(generator_version "10.0")
	(general
		(thickness 1.21888)
		(legacy_teardrops no)
	)
	(paper "A4")
	(title_block
		(title "timecard-v8 — TimeCard-DC-V8_EXP.PcbDoc")
		(comment 1 "Time Appliance Project (Time Card) / footprints 150-158 of 288")
	)
	(layers
		(0 "F.Cu" signal "TOP")
		(4 "In1.Cu" signal "SGND")
		(6 "In2.Cu" signal "IN1")
		(8 "In3.Cu" signal "IN2")
		(10 "In4.Cu" signal "SGND1")
		(2 "B.Cu" signal "BOTTOM")
		(9 "F.Adhes" user "F.Adhesive")
		(11 "B.Adhes" user "B.Adhesive")
		(13 "F.Paste" user "Top Paste")
		(15 "B.Paste" user "Bottom Paste")
		(5 "F.SilkS" user "Top Overlay")
		(7 "B.SilkS" user "Bottom Overlay")
		(1 "F.Mask" user "Top Solder")
		(3 "B.Mask" user "Bottom Solder")
		(17 "Dwgs.User" user "User.Drawings")
		(19 "Cmts.User" user "User.Comments")
		(21 "Eco1.User" user "User.Eco1")
		(23 "Eco2.User" user "User.Eco2")
		(25 "Edge.Cuts" user)
		(27 "Margin" user)
		(31 "F.CrtYd" user "Top Courtyard")
		(29 "B.CrtYd" user "Bottom Courtyard")
		(35 "F.Fab" user "Top Component Center")
		(33 "B.Fab" user "Bottom Component Center")
	)
	(footprint "Vault:FP-0402-L_1_0_1-W_0_5_0_1-IPC_C"
		(layer "F.Cu")
		(at 126.7261 83.2162 90)
		(property "Reference" "C96"
			(at 3.1286 0.026921 90)
			(unlocked yes)
			(layer "F.SilkS")
			(effects
				(font
					(size 0.762 0.762)
					(thickness 0.2286)
				)
			)
		)
		(property "Value" "0.1uF_25V_0402"
			(at -2.465551 9.839215 0)
			(unlocked yes)
			(layer "F.SilkS")
			(hide yes)
			(effects
				(font
					(size 0.762 0.762)
					(thickness 0.2286)
				)
			)
		)
		(sheetname "USBUart_DipSelects")
		(sheetfile "USBUart_DipSelects.kicad_sch")
		(duplicate_pad_numbers_are_jumpers no)
		(fp_line
			(start -0.65607 -0.7)
			(end 0.65607 -0.7)
			(stroke
				(width 0.2)
				(type solid)
			)
			(layer "F.SilkS")
		)
		(fp_line
			(start -0.65607 0.7)
			(end 0.65607 0.7)
			(stroke
				(width 0.2)
				(type solid)
			)
			(layer "F.SilkS")
		)
		(fp_line
			(start 0.75607 -0.4)
			(end 0.75607 0.4)
			(stroke
				(width 0.2)
				(type solid)
			)
			(layer "F.CrtYd")
		)
		(fp_line
			(start -0.75607 -0.4)
			(end 0.75607 -0.4)
			(stroke
				(width 0.2)
				(type solid)
			)
			(layer "F.CrtYd")
		)
		(fp_line
			(start -0.75607 -0.4)
			(end -0.75607 0.4)
			(stroke
				(width 0.2)
				(type solid)
			)
			(layer "F.CrtYd")
		)
		(fp_line
			(start -0.75607 0.4)
			(end 0.75607 0.4)
			(stroke
				(width 0.2)
				(type solid)
			)
			(layer "F.CrtYd")
		)
		(fp_line
			(start 0 -0.5)
			(end 0 0.5)
			(stroke
				(width 0.1)
				(type solid)
			)
			(layer "F.Fab")
		)
		(fp_line
			(start 0.75607 -0.4)
			(end 0.75607 0.4)
			(stroke
				(width 0.2)
				(type solid)
			)
			(layer "F.Fab")
		)
		(fp_line
			(start -0.75607 -0.4)
			(end 0.75607 -0.4)
			(stroke
				(width 0.2)
				(type solid)
			)
			(layer "F.Fab")
		)
		(fp_line
			(start -0.75607 -0.4)
			(end -0.75607 0.4)
			(stroke
				(width 0.2)
				(type solid)
			)
			(layer "F.Fab")
		)
		(fp_line
			(start -0.5 0)
			(end 0.5 0)
			(stroke
				(width 0.1)
				(type solid)
			)
			(layer "F.Fab")
		)
		(fp_line
			(start -0.75607 0.4)
			(end 0.75607 0.4)
			(stroke
				(width 0.2)
				(type solid)
			)
			(layer "F.Fab")
		)
		(fp_text user "${REFERENCE}"
			(at -0.00001 0.09601 90)
			(unlocked yes)
			(layer "F.Fab")
			(effects
				(font
					(face "Arial")
					(size 0.63 0.63)
					(thickness 0.1)
				)
				(justify left bottom)
			)
		)
		(pad "1" smd rect
			(at -0.36554 0 90)
			(size 0.58106 0.51213)
			(layers "F.Cu" "F.Mask" "F.Paste")
			(net "+3.3V")
			(solder_mask_margin 0)
			(solder_paste_margin 0)
		)
		(pad "2" smd rect
			(at 0.36554 0 90)
			(size 0.58106 0.51213)
			(layers "F.Cu" "F.Mask" "F.Paste")
			(net "GND")
			(solder_mask_margin 0)
			(solder_paste_margin 0)
		)
	)
	(footprint "Vault:RESC1005X40X25LL05T05"
		(layer "F.Cu")
		(at 191.2261 85.5162 180)
		(property "Reference" "R51"
			(at -0.528605 0.773079 0)
			(unlocked yes)
			(layer "F.SilkS")
			(effects
				(font
					(size 0.762 0.762)
					(thickness 0.2286)
				)
			)
		)
		(property "Value" "4.7K_0402"
			(at 1.612045 2.262391 180)
			(unlocked yes)
			(layer "F.SilkS")
			(hide yes)
			(effects
				(font
					(size 0.762 0.762)
					(thickness 0.2286)
				)
			)
		)
		(sheetname "GPS_IMU_SENSORS")
		(sheetfile "GPS_IMU_SENSORS.kicad_sch")
		(duplicate_pad_numbers_are_jumpers no)
		(pad "1" smd rect
			(at -0.4 0 270)
			(size 0.45 0.45)
			(layers "F.Cu" "F.Mask" "F.Paste")
			(net "+3.3V")
		)
		(pad "2" smd rect
			(at 0.4 0 270)
			(size 0.45 0.45)
			(layers "F.Cu" "F.Mask" "F.Paste")
			(net "NetR51_2")
		)
	)
	(footprint "Vault:RESC1005X40X25NL05T05"
		(layer "F.Cu")
		(at 233.6261 75.7162 90)
		(property "Reference" "R81"
			(at 0.271395 -4.526931 270)
			(unlocked yes)
			(layer "F.SilkS")
			(effects
				(font
					(size 0.762 0.762)
					(thickness 0.2286)
				)
			)
		)
		(property "Value" "27_1%_0402"
			(at -2.732271 7.37632 0)
			(unlocked yes)
			(layer "F.SilkS")
			(hide yes)
			(effects
				(font
					(size 0.762 0.762)
					(thickness 0.2286)
				)
			)
		)
		(sheetname "USBUart_DipSelects")
		(sheetfile "USBUart_DipSelects.kicad_sch")
		(duplicate_pad_numbers_are_jumpers no)
		(pad "1" smd rect
			(at -0.45 0 180)
			(size 0.55 0.55)
			(layers "F.Cu" "F.Mask" "F.Paste")
			(net "FTDI_USB_R_P")
		)
		(pad "2" smd rect
			(at 0.45 0 180)
			(size 0.55 0.55)
			(layers "F.Cu" "F.Mask" "F.Paste")
			(net "FTDI_USB_P")
		)
	)
	(footprint "Vault:RESC1005X40X25LL05T10"
		(layer "F.Cu")
		(at 235.7261 72.3162)
		(property "Reference" "R82"
			(at -2.0714 -0.173069 0)
			(unlocked yes)
			(layer "F.SilkS")
			(effects
				(font
					(size 0.762 0.762)
					(thickness 0.2286)
				)
			)
		)
		(property "Value" "10K_1%_0402"
			(at -2.579871 8.061915 270)
			(unlocked yes)
			(layer "F.SilkS")
			(hide yes)
			(effects
				(font
					(size 0.762 0.762)
					(thickness 0.2286)
				)
			)
		)
		(sheetname "USBUart_DipSelects")
		(sheetfile "USBUart_DipSelects.kicad_sch")
		(duplicate_pad_numbers_are_jumpers no)
		(pad "1" smd rect
			(at -0.375 0 90)
			(size 0.45 0.5)
			(layers "F.Cu" "F.Mask" "F.Paste")
			(net "NetC91_1")
		)
		(pad "2" smd rect
			(at 0.375 0 90)
			(size 0.45 0.5)
			(layers "F.Cu" "F.Mask" "F.Paste")
			(net "FTDI_VBUS")
		)
	)
	(footprint "Vault:FP-LTST-C191TBKT-MFG"
		(layer "F.Cu")
		(at 69.8761 52.1162 90)
		(property "Reference" "D3"
			(at -6.771395 0.026921 90)
			(unlocked yes)
			(layer "F.SilkS")
			(effects
				(font
					(size 0.762 0.762)
					(thickness 0.2286)
				)
			)
		)
		(property "Value" "BLUE"
			(at 1.2818 2.452871 90)
			(unlocked yes)
			(layer "F.SilkS")
			(hide yes)
			(effects
				(font
					(size 0.762 0.762)
					(thickness 0.2286)
				)
			)
		)
		(sheetname "USER_IO_STATUS")
		(sheetfile "USER_IO_STATUS.kicad_sch")
		(duplicate_pad_numbers_are_jumpers no)
		(fp_line
			(start -0.85 -0.8)
			(end 0.85 -0.8)
			(stroke
				(width 0.2)
				(type solid)
			)
			(layer "F.SilkS")
		)
		(fp_line
			(start -0.85 0.8)
			(end 0.85 0.8)
			(stroke
				(width 0.2)
				(type solid)
			)
			(layer "F.SilkS")
		)
		(fp_circle
			(center -1.75 0)
			(end -1.625 0)
			(stroke
				(width 0.25)
				(type solid)
			)
			(fill no)
			(layer "F.SilkS")
		)
		(fp_line
			(start 1.25 -0.55)
			(end 1.25 0.55)
			(stroke
				(width 0.2)
				(type solid)
			)
			(layer "F.CrtYd")
		)
		(fp_line
			(start -1.25 -0.55)
			(end 1.25 -0.55)
			(stroke
				(width 0.2)
				(type solid)
			)
			(layer "F.CrtYd")
		)
		(fp_line
			(start -1.25 -0.55)
			(end -1.25 0.55)
			(stroke
				(width 0.2)
				(type solid)
			)
			(layer "F.CrtYd")
		)
		(fp_line
			(start -1.25 0.55)
			(end 1.25 0.55)
			(stroke
				(width 0.2)
				(type solid)
			)
			(layer "F.CrtYd")
		)
		(fp_line
			(start 1.25 -0.55)
			(end 1.25 0.55)
			(stroke
				(width 0.2)
				(type solid)
			)
			(layer "F.Fab")
		)
		(fp_line
			(start -1.25 -0.55)
			(end 1.25 -0.55)
			(stroke
				(width 0.2)
				(type solid)
			)
			(layer "F.Fab")
		)
		(fp_line
			(start -1.25 -0.55)
			(end -1.25 0.55)
			(stroke
				(width 0.2)
				(type solid)
			)
			(layer "F.Fab")
		)
		(fp_line
			(start 0 -0.5)
			(end 0 0.5)
			(stroke
				(width 0.1)
				(type solid)
			)
			(layer "F.Fab")
		)
		(fp_line
			(start -0.5 0)
			(end 0.5 0)
			(stroke
				(width 0.1)
				(type solid)
			)
			(layer "F.Fab")
		)
		(fp_line
			(start -1.25 0.55)
			(end 1.25 0.55)
			(stroke
				(width 0.2)
				(type solid)
			)
			(layer "F.Fab")
		)
		(fp_text user "${REFERENCE}"
			(at 0 0.28424 90)
			(unlocked yes)
			(layer "F.Fab")
			(effects
				(font
					(face "Arial")
					(size 0.63 0.63)
					(thickness 0.1)
				)
				(justify left bottom)
			)
		)
		(pad "1" smd rect
			(at -0.75 0 90)
			(size 0.8 0.8)
			(layers "F.Cu" "F.Mask" "F.Paste")
			(net "NetD3_1")
			(solder_mask_margin 0)
			(solder_paste_margin 0)
		)
		(pad "2" smd rect
			(at 0.75 0 90)
			(size 0.8 0.8)
			(layers "F.Cu" "F.Mask" "F.Paste")
			(net "+3.3V")
			(solder_mask_margin 0)
			(solder_paste_margin 0)
		)
	)
	(footprint "Resistors:RESC2012X50N"
		(layer "F.Cu")
		(at 224.9261 142.2162 -90)
		(property "Reference" "R21"
			(at -1.25 -1.406655 270)
			(unlocked yes)
			(layer "F.SilkS")
			(effects
				(font
					(size 0.762 0.762)
					(thickness 0.2286)
				)
				(justify left bottom)
			)
		)
		(property "Value" "CRCW080533R0FKEA"
			(at -3.179155 -11.2251 0)
			(unlocked yes)
			(layer "F.SilkS")
			(hide yes)
			(effects
				(font
					(size 0.762 0.762)
					(thickness 0.2286)
				)
				(justify left bottom)
			)
		)
		(sheetname "PCIe_JTAG")
		(sheetfile "PCIe_JTAG.kicad_sch")
		(duplicate_pad_numbers_are_jumpers no)
		(fp_line
			(start 0 0.762)
			(end 0 -0.762)
			(stroke
				(width 0.1524)
				(type solid)
			)
			(layer "F.SilkS")
		)
		(pad "1" smd rect
			(at -1 0)
			(size 1.45 0.95)
			(layers "F.Cu" "F.Mask" "F.Paste")
			(net "FPGA_TDI")
		)
		(pad "2" smd rect
			(at 1 0)
			(size 1.45 0.95)
			(layers "F.Cu" "F.Mask" "F.Paste")
			(net "NetR21_2")
		)
	)
	(footprint "Vault:RESC1005X40X25LL05T05"
		(layer "F.Cu")
		(at 80.3261 83.1162)
		(property "Reference" "R109"
			(at -2.8714 -0.073069 0)
			(unlocked yes)
			(layer "F.SilkS")
			(effects
				(font
					(size 0.762 0.762)
					(thickness 0.2286)
				)
			)
		)
		(property "Value" "4.7K_0402"
			(at -2.352802 6.563805 270)
			(unlocked yes)
			(layer "F.SilkS")
			(hide yes)
			(effects
				(font
					(size 1.524 1.524)
					(thickness 0.254)
				)
			)
		)
		(sheetname "USER_IO_STATUS")
		(sheetfile "USER_IO_STATUS.kicad_sch")
		(duplicate_pad_numbers_are_jumpers no)
		(pad "1" smd rect
			(at -0.4 0 90)
			(size 0.45 0.45)
			(layers "F.Cu" "F.Mask" "F.Paste")
			(net "+3.3V")
		)
		(pad "2" smd rect
			(at 0.4 0 90)
			(size 0.45 0.45)
			(layers "F.Cu" "F.Mask" "F.Paste")
			(net "NetR40_2")
		)
	)
	(footprint "Vault:FP-0402-L_1_0_1-W_0_5_0_1-IPC_C"
		(layer "F.Cu")
		(at 202.8261 126.2162 180)
		(property "Reference" "C71"
			(at 3.271395 -4.326921 0)
			(unlocked yes)
			(layer "F.SilkS")
			(effects
				(font
					(size 0.762 0.762)
					(thickness 0.2286)
				)
			)
		)
		(property "Value" "0.1uF_25V_0402"
			(at 9.788415 2.414751 180)
			(unlocked yes)
			(layer "F.SilkS")
			(hide yes)
			(effects
				(font
					(size 0.762 0.762)
					(thickness 0.2286)
				)
			)
		)
		(sheetname "POWER")
		(sheetfile "POWER.kicad_sch")
		(duplicate_pad_numbers_are_jumpers no)
		(fp_line
			(start 0.65607 0.7)
			(end -0.65607 0.7)
			(stroke
				(width 0.2)
				(type solid)
			)
			(layer "F.SilkS")
		)
		(fp_line
			(start 0.65607 -0.7)
			(end -0.65607 -0.7)
			(stroke
				(width 0.2)
				(type solid)
			)
			(layer "F.SilkS")
		)
		(fp_line
			(start 0.75607 0.4)
			(end -0.75607 0.4)
			(stroke
				(width 0.2)
				(type solid)
			)
			(layer "F.CrtYd")
		)
		(fp_line
			(start 0.75607 -0.4)
			(end 0.75607 0.4)
			(stroke
				(width 0.2)
				(type solid)
			)
			(layer "F.CrtYd")
		)
		(fp_line
			(start 0.75607 -0.4)
			(end -0.75607 -0.4)
			(stroke
				(width 0.2)
				(type solid)
			)
			(layer "F.CrtYd")
		)
		(fp_line
			(start -0.75607 -0.4)
			(end -0.75607 0.4)
			(stroke
				(width 0.2)
				(type solid)
			)
			(layer "F.CrtYd")
		)
		(fp_line
			(start 0.75607 0.4)
			(end -0.75607 0.4)
			(stroke
				(width 0.2)
				(type solid)
			)
			(layer "F.Fab")
		)
		(fp_line
			(start 0.75607 -0.4)
			(end 0.75607 0.4)
			(stroke
				(width 0.2)
				(type solid)
			)
			(layer "F.Fab")
		)
		(fp_line
			(start 0.75607 -0.4)
			(end -0.75607 -0.4)
			(stroke
				(width 0.2)
				(type solid)
			)
			(layer "F.Fab")
		)
		(fp_line
			(start 0.5 0)
			(end -0.5 0)
			(stroke
				(width 0.1)
				(type solid)
			)
			(layer "F.Fab")
		)
		(fp_line
			(start 0 -0.5)
			(end 0 0.5)
			(stroke
				(width 0.1)
				(type solid)
			)
			(layer "F.Fab")
		)
		(fp_line
			(start -0.75607 -0.4)
			(end -0.75607 0.4)
			(stroke
				(width 0.2)
				(type solid)
			)
			(layer "F.Fab")
		)
		(fp_text user "${REFERENCE}"
			(at -0.00001 0.09601 180)
			(unlocked yes)
			(layer "F.Fab")
			(effects
				(font
					(face "Arial")
					(size 0.63 0.63)
					(thickness 0.1)
				)
				(justify left bottom)
			)
		)
		(pad "1" smd rect
			(at -0.36554 0 180)
			(size 0.58106 0.51213)
			(layers "F.Cu" "F.Mask" "F.Paste")
			(net "NetC71_1")
			(solder_mask_margin 0)
			(solder_paste_margin 0)
		)
		(pad "2" smd rect
			(at 0.36554 0 180)
			(size 0.58106 0.51213)
			(layers "F.Cu" "F.Mask" "F.Paste")
			(net "GND")
			(solder_mask_margin 0)
			(solder_paste_margin 0)
		)
	)
	(footprint "Vault:FP-MK212BG-MFG"
		(layer "F.Cu")
		(at 75.1261 65.1162 90)
		(property "Reference" "C42"
			(at 0.2286 -1.773079 90)
			(unlocked yes)
			(layer "F.SilkS")
			(effects
				(font
					(size 0.762 0.762)
					(thickness 0.2286)
				)
			)
		)
		(property "Value" "10uF"
			(at -3.240271 2.22164 0)
			(unlocked yes)
			(layer "F.SilkS")
			(hide yes)
			(effects
				(font
					(size 0.762 0.762)
					(thickness 0.2286)
				)
			)
		)
		(sheetname "GPS_IMU_SENSORS")
		(sheetfile "GPS_IMU_SENSORS.kicad_sch")
		(duplicate_pad_numbers_are_jumpers no)
		(fp_line
			(start -0.125 -0.725)
			(end 0.125 -0.725)
			(stroke
				(width 0.2)
				(type solid)
			)
			(layer "F.SilkS")
		)
		(fp_line
			(start -0.125 0.725)
			(end 0.125 0.725)
			(stroke
				(width 0.2)
				(type solid)
			)
			(layer "F.SilkS")
		)
		(fp_line
			(start 1.6 -0.825)
			(end 1.6 0.825)
			(stroke
				(width 0.2)
				(type solid)
			)
			(layer "F.CrtYd")
		)
		(fp_line
			(start -1.6 -0.825)
			(end 1.6 -0.825)
			(stroke
				(width 0.2)
				(type solid)
			)
			(layer "F.CrtYd")
		)
		(fp_line
			(start -1.6 -0.825)
			(end -1.6 0.825)
			(stroke
				(width 0.2)
				(type solid)
			)
			(layer "F.CrtYd")
		)
		(fp_line
			(start -1.6 0.825)
			(end 1.6 0.825)
			(stroke
				(width 0.2)
				(type solid)
			)
			(layer "F.CrtYd")
		)
		(fp_line
			(start 1.6 -0.825)
			(end 1.6 0.825)
			(stroke
				(width 0.2)
				(type solid)
			)
			(layer "F.Fab")
		)
		(fp_line
			(start -1.6 -0.825)
			(end 1.6 -0.825)
			(stroke
				(width 0.2)
				(type solid)
			)
			(layer "F.Fab")
		)
		(fp_line
			(start -1.6 -0.825)
			(end -1.6 0.825)
			(stroke
				(width 0.2)
				(type solid)
			)
			(layer "F.Fab")
		)
		(fp_line
			(start 0 -0.5)
			(end 0 0.5)
			(stroke
				(width 0.1)
				(type solid)
			)
			(layer "F.Fab")
		)
		(fp_line
			(start -0.5 0)
			(end 0.5 0)
			(stroke
				(width 0.1)
				(type solid)
			)
			(layer "F.Fab")
		)
		(fp_line
			(start -1.6 0.825)
			(end 1.6 0.825)
			(stroke
				(width 0.2)
				(type solid)
			)
			(layer "F.Fab")
		)
		(fp_text user "${REFERENCE}"
			(at -0.00001 0.09601 90)
			(unlocked yes)
			(layer "F.Fab")
			(effects
				(font
					(face "Arial")
					(size 0.63 0.63)
					(thickness 0.1)
				)
				(justify left bottom)
			)
		)
		(pad "1" smd rect
			(at -1 0 90)
			(size 1 1.25)
			(layers "F.Cu" "F.Mask" "F.Paste")
			(net "+5.0V")
			(solder_mask_margin 0)
			(solder_paste_margin 0)
		)
		(pad "2" smd rect
			(at 1 0 90)
			(size 1 1.25)
			(layers "F.Cu" "F.Mask" "F.Paste")
			(net "GND")
			(solder_mask_margin 0)
			(solder_paste_margin 0)
		)
	)
)
